# T6G (Grand Teton) — schematic netlist excerpt (pin names and nets, part order shuffled) for the footprints in the layout excerpt that follows; sources: Cadence DE-HDL packaged netlist, KiCad conversion of 04192023_DAF0TMB3IC0_F0TG_MB_C_brd_V02_OCP.brd

PC641  Q_CAP  0.22UF 25V 10% X7R  pkg C0402  page 269 : A = SW_P1V8_AUX_BT_R ; B = SW_P1V8_AUX_PH
R5051  Q_RES  0 5% EMPTY  pkg 0402LF  page 187 : A = P3V3_RTC_AUX ; B = P1V5_BAT_IN

(kicad_pcb
	(version 20260206)
	(generator "pcbnew")
	(generator_version "10.0")
	(general
		(thickness 1.6)
		(legacy_teardrops no)
	)
	(paper "A4")
	(title_block
		(title "04192023_DAF0TMB3IC0_F0TG_MB_C_brd_V02_OCP.brd")
		(comment 1 "Grand Teton / footprints 633-634 of 8354")
	)
	(layers
		(0 "F.Cu" signal "TOP")
		(4 "In1.Cu" signal "GND")
		(6 "In2.Cu" signal "IN1")
		(8 "In3.Cu" signal "GND1")
		(10 "In4.Cu" signal "IN2")
		(12 "In5.Cu" signal "GND2")
		(14 "In6.Cu" signal "IN3")
		(16 "In7.Cu" signal "GND3")
		(18 "In8.Cu" signal "VCC")
		(20 "In9.Cu" signal "VCC1")
		(22 "In10.Cu" signal "GND4")
		(24 "In11.Cu" signal "IN4")
		(26 "In12.Cu" signal "GND5")
		(28 "In13.Cu" signal "IN5")
		(30 "In14.Cu" signal "GND6")
		(32 "In15.Cu" signal "IN6")
		(34 "In16.Cu" signal "GND7")
		(2 "B.Cu" signal "BOTTOM")
		(9 "F.Adhes" user "F.Adhesive")
		(11 "B.Adhes" user "B.Adhesive")
		(13 "F.Paste" user "Package Geometry/Pastemask Top")
		(15 "B.Paste" user "Package Geometry/Pastemask Bottom")
		(5 "F.SilkS" user "Ref Des/Silkscreen Top")
		(7 "B.SilkS" user "Ref Des/Silkscreen Bottom")
		(1 "F.Mask" user "Board Geometry/Soldermask Top")
		(3 "B.Mask" user "Board Geometry/Soldermask Bottom")
		(17 "Dwgs.User" user "User.Drawings")
		(19 "Cmts.User" user "User.Comments")
		(21 "Eco1.User" user "User.Eco1")
		(23 "Eco2.User" user "User.Eco2")
		(25 "Edge.Cuts" user "Board Geometry/Outline")
		(27 "Margin" user)
		(31 "F.CrtYd" user "Package Geometry/Place Bound Top")
		(29 "B.CrtYd" user "Package Geometry/Place Bound Bottom")
		(35 "F.Fab" user "Ref Des/Assembly Top")
		(33 "B.Fab" user "Ref Des/Assembly Bottom")
	)
	(footprint ""
		(layer "F.Cu")
		(at 301.393098 -25.322276 180)
		(property "Reference" "R5051"
			(at 0 0 180)
			(layer "F.SilkS")
			(hide yes)
			(effects
				(font
					(size 1.27 1.27)
				)
			)
		)
		(property "Value" ""
			(at 0 0 180)
			(layer "F.Fab")
			(effects
				(font
					(size 1.27 1.27)
				)
			)
		)
		(duplicate_pad_numbers_are_jumpers no)
		(fp_line
			(start 0.7874 0.4064)
			(end -0.7874 0.4064)
			(stroke
				(width 0.1524)
				(type default)
			)
			(layer "F.SilkS")
		)
		(fp_line
			(start 0.7874 -0.4064)
			(end 0.7874 0.4064)
			(stroke
				(width 0.1524)
				(type default)
			)
			(layer "F.SilkS")
		)
		(fp_line
			(start -0.7874 0.4064)
			(end -0.7874 -0.4064)
			(stroke
				(width 0.1524)
				(type default)
			)
			(layer "F.SilkS")
		)
		(fp_line
			(start -0.7874 -0.4064)
			(end 0.7874 -0.4064)
			(stroke
				(width 0.1524)
				(type default)
			)
			(layer "F.SilkS")
		)
		(fp_line
			(start 0.67945 0.3048)
			(end 0.120396 0.3048)
			(stroke
				(width 0.1)
				(type default)
			)
			(layer "F.Fab")
		)
		(fp_line
			(start 0.67945 -0.3048)
			(end 0.67945 0.3048)
			(stroke
				(width 0.1)
				(type default)
			)
			(layer "F.Fab")
		)
		(fp_line
			(start 0.12065 -0.2794)
			(end 0.12065 -0.3048)
			(stroke
				(width 0.1)
				(type default)
			)
			(layer "F.Fab")
		)
		(fp_line
			(start 0.12065 -0.3048)
			(end 0.67945 -0.3048)
			(stroke
				(width 0.1)
				(type default)
			)
			(layer "F.Fab")
		)
		(fp_line
			(start 0.120396 0.3048)
			(end 0.120396 0.2794)
			(stroke
				(width 0.1)
				(type default)
			)
			(layer "F.Fab")
		)
		(fp_line
			(start 0.120396 0.2794)
			(end -0.12065 0.2794)
			(stroke
				(width 0.1)
				(type default)
			)
			(layer "F.Fab")
		)
		(fp_line
			(start -0.12065 0.3048)
			(end -0.67945 0.3048)
			(stroke
				(width 0.1)
				(type default)
			)
			(layer "F.Fab")
		)
		(fp_line
			(start -0.12065 0.2794)
			(end -0.12065 0.3048)
			(stroke
				(width 0.1)
				(type default)
			)
			(layer "F.Fab")
		)
		(fp_line
			(start -0.12065 -0.2794)
			(end 0.12065 -0.2794)
			(stroke
				(width 0.1)
				(type default)
			)
			(layer "F.Fab")
		)
		(fp_line
			(start -0.12065 -0.305054)
			(end -0.12065 -0.2794)
			(stroke
				(width 0.1)
				(type default)
			)
			(layer "F.Fab")
		)
		(fp_line
			(start -0.67945 0.3048)
			(end -0.67945 -0.305054)
			(stroke
				(width 0.1)
				(type default)
			)
			(layer "F.Fab")
		)
		(fp_line
			(start -0.67945 -0.305054)
			(end -0.12065 -0.305054)
			(stroke
				(width 0.1)
				(type default)
			)
			(layer "F.Fab")
		)
		(pad "1" smd circle
			(at -0.40005 0 180)
			(size 0 0)
			(layers "F.Cu" "F.Mask" "F.Paste")
			(net "P3V3_RTC_AUX")
		)
		(pad "2" smd circle
			(at 0.40005 0 180)
			(size 0 0)
			(layers "F.Cu" "F.Mask" "F.Paste")
			(net "P1V5_BAT_IN")
		)
	)
	(footprint ""
		(layer "F.Cu")
		(at 146.186652 -78.537562 90)
		(property "Reference" "PC641"
			(at 0 0 90)
			(layer "F.SilkS")
			(hide yes)
			(effects
				(font
					(size 1.27 1.27)
				)
			)
		)
		(property "Value" ""
			(at 0 0 90)
			(layer "F.Fab")
			(effects
				(font
					(size 1.27 1.27)
				)
			)
		)
		(duplicate_pad_numbers_are_jumpers no)
		(fp_line
			(start 0.7874 -0.4064)
			(end 0.7874 0.4064)
			(stroke
				(width 0.1524)
				(type default)
			)
			(layer "F.SilkS")
		)
		(fp_line
			(start -0.7874 -0.4064)
			(end 0.7874 -0.4064)
			(stroke
				(width 0.1524)
				(type default)
			)
			(layer "F.SilkS")
		)
		(fp_line
			(start 0.7874 0.4064)
			(end -0.7874 0.4064)
			(stroke
				(width 0.1524)
				(type default)
			)
			(layer "F.SilkS")
		)
		(fp_line
			(start -0.7874 0.4064)
			(end -0.7874 -0.4064)
			(stroke
				(width 0.1524)
				(type default)
			)
			(layer "F.SilkS")
		)
		(fp_line
			(start -0.12065 -0.305054)
			(end -0.12065 -0.2794)
			(stroke
				(width 0.1)
				(type default)
			)
			(layer "F.Fab")
		)
		(fp_line
			(start -0.67945 -0.305054)
			(end -0.12065 -0.305054)
			(stroke
				(width 0.1)
				(type default)
			)
			(layer "F.Fab")
		)
		(fp_line
			(start 0.67945 -0.3048)
			(end 0.67945 0.3048)
			(stroke
				(width 0.1)
				(type default)
			)
			(layer "F.Fab")
		)
		(fp_line
			(start 0.12065 -0.3048)
			(end 0.67945 -0.3048)
			(stroke
				(width 0.1)
				(type default)
			)
			(layer "F.Fab")
		)
		(fp_line
			(start 0.12065 -0.2794)
			(end 0.12065 -0.3048)
			(stroke
				(width 0.1)
				(type default)
			)
			(layer "F.Fab")
		)
		(fp_line
			(start -0.12065 -0.2794)
			(end 0.12065 -0.2794)
			(stroke
				(width 0.1)
				(type default)
			)
			(layer "F.Fab")
		)
		(fp_line
			(start 0.120396 0.2794)
			(end -0.12065 0.2794)
			(stroke
				(width 0.1)
				(type default)
			)
			(layer "F.Fab")
		)
		(fp_line
			(start -0.12065 0.2794)
			(end -0.12065 0.3048)
			(stroke
				(width 0.1)
				(type default)
			)
			(layer "F.Fab")
		)
		(fp_line
			(start 0.67945 0.3048)
			(end 0.120396 0.3048)
			(stroke
				(width 0.1)
				(type default)
			)
			(layer "F.Fab")
		)
		(fp_line
			(start 0.120396 0.3048)
			(end 0.120396 0.2794)
			(stroke
				(width 0.1)
				(type default)
			)
			(layer "F.Fab")
		)
		(fp_line
			(start -0.12065 0.3048)
			(end -0.67945 0.3048)
			(stroke
				(width 0.1)
				(type default)
			)
			(layer "F.Fab")
		)
		(fp_line
			(start -0.67945 0.3048)
			(end -0.67945 -0.305054)
			(stroke
				(width 0.1)
				(type default)
			)
			(layer "F.Fab")
		)
		(pad "1" smd circle
			(at -0.40005 0 90)
			(size 0 0)
			(layers "F.Cu" "F.Mask" "F.Paste")
			(net "SW_P1V8_AUX_BT_R")
		)
		(pad "2" smd circle
			(at 0.40005 0 90)
			(size 0 0)
			(layers "F.Cu" "F.Mask" "F.Paste")
			(net "SW_P1V8_AUX_PH")
		)
	)
)
